(kicad_pcb
	(version 20241229)
	(generator "pcbnew")
	(generator_version "9.0")
	(general
		(thickness 1.62)
		(legacy_teardrops no)
	)
	(paper "A4")
	(title_block
		(title "OCuLink to 10GbE adapter")
		(date "2026-02-23")
		(rev "1.1.0")
		(company "Antmicro Ltd")
		(comment 1 "www.antmicro.com")
		(comment 9 "footprints 147-151 of 510")
	)
	(layers
		(0 "F.Cu" signal)
		(4 "In1.Cu" signal)
		(6 "In2.Cu" signal)
		(8 "In3.Cu" signal)
		(10 "In4.Cu" signal)
		(12 "In5.Cu" signal)
		(14 "In6.Cu" signal)
		(2 "B.Cu" signal)
		(9 "F.Adhes" user "F.Adhesive")
		(11 "B.Adhes" user "B.Adhesive")
		(13 "F.Paste" user)
		(15 "B.Paste" user)
		(5 "F.SilkS" user "F.Silkscreen")
		(7 "B.SilkS" user "B.Silkscreen")
		(1 "F.Mask" user)
		(3 "B.Mask" user)
		(17 "Dwgs.User" user "User.Drawings")
		(19 "Cmts.User" user "User.Comments")
		(21 "Eco1.User" user "User.Eco1")
		(23 "Eco2.User" user "User.Eco2")
		(25 "Edge.Cuts" user)
		(27 "Margin" user)
		(31 "F.CrtYd" user "F.Courtyard")
		(29 "B.CrtYd" user "B.Courtyard")
		(35 "F.Fab" user)
		(33 "B.Fab" user)
	)
	(footprint "antmicro-footprints:L_Bourns-SRP4021HMT"
		(layer "F.Cu")
		(at 60.249999 111.549999 180)
		(property "Reference" "L4"
			(at -2.620001 -2.240001 0)
			(layer "F.SilkS")
			(effects
				(font
					(size 0.7 0.7)
					(thickness 0.15)
				)
				(justify right top)
			)
		)
		(property "Value" "L_1u_10A_Bourns-SRP4021HMT"
			(at -2.85 3.4 0)
			(layer "F.Fab")
			(hide yes)
			(effects
				(font
					(size 0.7 0.7)
					(thickness 0.15)
				)
				(justify right top)
			)
		)
		(property "Datasheet" "https://www.mouser.com/datasheet/2/54/Bourns_04_01_2025_SRP4021HMT_Datasheet-3580094.pdf"
			(at 0 0 0)
			(layer "F.Fab")
			(hide yes)
			(effects
				(font
					(size 0.7 0.7)
					(thickness 0.15)
				)
				(justify right top)
			)
		)
		(property "Description" "Power Inductors - SMD Ind,4.1x4.2x1.9mm,1uH+/-20%,10A, Shielded"
			(at 0 0 0)
			(layer "F.Fab")
			(hide yes)
			(effects
				(font
					(size 0.7 0.7)
					(thickness 0.15)
				)
				(justify right top)
			)
		)
		(property "Val" "1u/10A"
			(at 0 0 180)
			(unlocked yes)
			(layer "F.Fab")
			(hide yes)
			(effects
				(font
					(size 1 1)
					(thickness 0.15)
				)
			)
		)
		(property "Manufacturer" "Bourns"
			(at 0 0 180)
			(unlocked yes)
			(layer "F.Fab")
			(hide yes)
			(effects
				(font
					(size 1 1)
					(thickness 0.15)
				)
			)
		)
		(property "MPN" "SRP4021HMT-1R0M"
			(at 0 0 180)
			(unlocked yes)
			(layer "F.Fab")
			(hide yes)
			(effects
				(font
					(size 1 1)
					(thickness 0.15)
				)
			)
		)
		(property "ISat" ""
			(at 0 0 180)
			(unlocked yes)
			(layer "F.Fab")
			(hide yes)
			(effects
				(font
					(size 1 1)
					(thickness 0.15)
				)
			)
		)
		(property "Isat" "8A"
			(at 0 0 180)
			(unlocked yes)
			(layer "F.Fab")
			(hide yes)
			(effects
				(font
					(size 1 1)
					(thickness 0.15)
				)
			)
		)
		(property "IMax" ""
			(at 0 0 180)
			(unlocked yes)
			(layer "F.Fab")
			(hide yes)
			(effects
				(font
					(size 1 1)
					(thickness 0.15)
				)
			)
		)
		(property "Imax" "10A"
			(at 0 0 180)
			(unlocked yes)
			(layer "F.Fab")
			(hide yes)
			(effects
				(font
					(size 1 1)
					(thickness 0.15)
				)
			)
		)
		(property "Size" "4.2x4.1"
			(at 0 0 180)
			(unlocked yes)
			(layer "F.Fab")
			(hide yes)
			(effects
				(font
					(size 1 1)
					(thickness 0.15)
				)
			)
		)
		(property "Author" "Antmicro"
			(at 0 0 180)
			(unlocked yes)
			(layer "F.Fab")
			(hide yes)
			(effects
				(font
					(size 1 1)
					(thickness 0.15)
				)
			)
		)
		(property "License" "Apache-2.0"
			(at 0 0 180)
			(unlocked yes)
			(layer "F.Fab")
			(hide yes)
			(effects
				(font
					(size 1 1)
					(thickness 0.15)
				)
			)
		)
		(sheetname "/Power/")
		(sheetfile "power.kicad_sch")
		(attr smd)
		(fp_line
			(start -0.8 2.05)
			(end 0.8 2.05)
			(stroke
				(width 0.15)
				(type solid)
			)
			(layer "F.SilkS")
		)
		(fp_line
			(start -0.8 -2.05)
			(end 0.8 -2.05)
			(stroke
				(width 0.15)
				(type solid)
			)
			(layer "F.SilkS")
		)
		(fp_rect
			(start -2.85 -2.3)
			(end 2.85 2.3)
			(stroke
				(width 0.05)
				(type solid)
			)
			(fill no)
			(layer "F.CrtYd")
		)
		(fp_rect
			(start -2 -2.05)
			(end 2 2.05)
			(stroke
				(width 0.15)
				(type solid)
			)
			(fill no)
			(layer "F.Fab")
		)
		(pad "1" smd rect
			(at 1.85 0)
			(size 1.5 3.5)
			(layers "F.Cu" "F.Mask" "F.Paste")
			(net 337 "/Power/1V0_SW")
			(pintype "passive")
		)
		(pad "2" smd rect
			(at -1.85 0)
			(size 1.5 3.5)
			(layers "F.Cu" "F.Mask" "F.Paste")
			(net 312 "/Power/+1V0_OUT")
			(pintype "passive")
		)
	)
	(footprint "antmicro-footprints:TSSOP-8_3x3mm_P0.65mm"
		(layer "F.Cu")
		(at 94.8 113.3 180)
		(property "Reference" "U7"
			(at -0.75 -1.9 0)
			(layer "F.SilkS")
			(effects
				(font
					(size 0.7 0.7)
					(thickness 0.15)
				)
				(justify right top)
			)
		)
		(property "Value" "NTS0102_TSSOP"
			(at 0 2.8 0)
			(layer "F.Fab")
			(hide yes)
			(effects
				(font
					(size 0.7 0.7)
					(thickness 0.15)
				)
				(justify right top)
			)
		)
		(property "Datasheet" "https://www.mouser.com/datasheet/2/302/NTS0102-1127324.pdf"
			(at 0 0 0)
			(layer "F.Fab")
			(hide yes)
			(effects
				(font
					(size 1.27 1.27)
					(thickness 0.15)
				)
			)
		)
		(property "Description" "Transceiver, 1.65 V to 3.6 V, TSSOP-8"
			(at 0 0 0)
			(layer "F.Fab")
			(hide yes)
			(effects
				(font
					(size 1.27 1.27)
					(thickness 0.15)
				)
			)
		)
		(property "MPN" "NTS0102DP"
			(at 0 0 180)
			(unlocked yes)
			(layer "F.Fab")
			(hide yes)
			(effects
				(font
					(size 1 1)
					(thickness 0.15)
				)
			)
		)
		(property "Manufacturer" "NXP"
			(at 0 0 180)
			(unlocked yes)
			(layer "F.Fab")
			(hide yes)
			(effects
				(font
					(size 1 1)
					(thickness 0.15)
				)
			)
		)
		(property "Author" "Antmicro"
			(at 0 0 180)
			(unlocked yes)
			(layer "F.Fab")
			(hide yes)
			(effects
				(font
					(size 1 1)
					(thickness 0.15)
				)
			)
		)
		(property "License" "Apache-2.0"
			(at 0 0 180)
			(unlocked yes)
			(layer "F.Fab")
			(hide yes)
			(effects
				(font
					(size 1 1)
					(thickness 0.15)
				)
			)
		)
		(sheetname "/X710-AT2 Misc/")
		(sheetfile "x710-at2-mics.kicad_sch")
		(attr smd)
		(fp_line
			(start -1.525 -1.537)
			(end 1.552 -1.539)
			(stroke
				(width 0.15)
				(type solid)
			)
			(layer "F.SilkS")
		)
		(fp_line
			(start -1.55 1.561)
			(end 1.552 1.561)
			(stroke
				(width 0.15)
				(type solid)
			)
			(layer "F.SilkS")
		)
		(fp_circle
			(center -1.87 -1.4)
			(end -1.82 -1.4)
			(stroke
				(width 0.15)
				(type solid)
			)
			(fill yes)
			(layer "F.SilkS")
		)
		(fp_rect
			(start -3.15 -1.789)
			(end 3.15 1.811)
			(stroke
				(width 0.05)
				(type solid)
			)
			(fill no)
			(layer "F.CrtYd")
		)
		(fp_line
			(start 1.552 -1.539)
			(end 1.552 1.561)
			(stroke
				(width 0.15)
				(type solid)
			)
			(layer "F.Fab")
		)
		(fp_line
			(start -0.949 -1.539)
			(end 1.552 -1.539)
			(stroke
				(width 0.15)
				(type solid)
			)
			(layer "F.Fab")
		)
		(fp_line
			(start -1.55 1.561)
			(end 1.552 1.561)
			(stroke
				(width 0.15)
				(type solid)
			)
			(layer "F.Fab")
		)
		(fp_line
			(start -1.55 -0.937)
			(end -0.949 -1.539)
			(stroke
				(width 0.15)
				(type solid)
			)
			(layer "F.Fab")
		)
		(fp_line
			(start -1.55 -0.937)
			(end -1.55 1.561)
			(stroke
				(width 0.15)
				(type solid)
			)
			(layer "F.Fab")
		)
		(pad "1" smd roundrect
			(at -2.148 -0.962 180)
			(size 1.47 0.4)
			(layers "F.Cu" "F.Mask" "F.Paste")
			(roundrect_rratio 0.25)
			(net 158 "Net-(U7-B_{2})")
			(pinfunction "B_{2}")
			(pintype "bidirectional")
		)
		(pad "2" smd roundrect
			(at -2.148 -0.313 180)
			(size 1.47 0.4)
			(layers "F.Cu" "F.Mask" "F.Paste")
			(roundrect_rratio 0.25)
			(net 28 "GND")
			(pinfunction "GND")
			(pintype "power_in")
		)
		(pad "3" smd roundrect
			(at -2.148 0.338 180)
			(size 1.47 0.4)
			(layers "F.Cu" "F.Mask" "F.Paste")
			(roundrect_rratio 0.25)
			(net 18 "+1V88")
			(pinfunction "VCC_{A}")
			(pintype "power_in")
		)
		(pad "4" smd roundrect
			(at -2.148 0.987 180)
			(size 1.47 0.4)
			(layers "F.Cu" "F.Mask" "F.Paste")
			(roundrect_rratio 0.25)
			(net 157 "Net-(U7-A_{2})")
			(pinfunction "A_{2}")
			(pintype "bidirectional")
		)
		(pad "5" smd roundrect
			(at 2.151 0.987 180)
			(size 1.47 0.4)
			(layers "F.Cu" "F.Mask" "F.Paste")
			(roundrect_rratio 0.25)
			(net 384 "/X710-AT2 Misc/~{PHY_RESET}")
			(pinfunction "A_{1}")
			(pintype "bidirectional")
		)
		(pad "6" smd roundrect
			(at 2.151 0.338 180)
			(size 1.47 0.4)
			(layers "F.Cu" "F.Mask" "F.Paste")
			(roundrect_rratio 0.25)
			(net 18 "+1V88")
			(pinfunction "OE")
			(pintype "input")
		)
		(pad "7" smd roundrect
			(at 2.151 -0.313 180)
			(size 1.47 0.4)
			(layers "F.Cu" "F.Mask" "F.Paste")
			(roundrect_rratio 0.25)
			(net 7 "+3V3")
			(pinfunction "VCC_{B}")
			(pintype "power_in")
		)
		(pad "8" smd roundrect
			(at 2.151 -0.962 180)
			(size 1.47 0.4)
			(layers "F.Cu" "F.Mask" "F.Paste")
			(roundrect_rratio 0.25)
			(net 380 "/X710-AT2 10GbE/~{PHY_RESET_3V3}")
			(pinfunction "B_{1}")
			(pintype "bidirectional")
		)
	)
	(footprint "antmicro-footprints:C_0603_1608Metric_EIA"
		(layer "F.Cu")
		(at 63.199999 85.450001 180)
		(descr "Capacitor SMD 0603, IPC-7351 Density Level A")
		(tags "Capacitor 0603")
		(property "Reference" "C17"
			(at -0.890001 2.760001 0)
			(layer "F.SilkS")
			(effects
				(font
					(size 0.7 0.7)
					(thickness 0.15)
				)
				(justify right top)
			)
		)
		(property "Value" "C_22u_16V_0603"
			(at -1.42757 1.770288 0)
			(layer "F.Fab")
			(hide yes)
			(effects
				(font
					(size 0.7 0.7)
					(thickness 0.15)
				)
				(justify right top)
			)
		)
		(property "Datasheet" "https://product.samsungsem.com/mlcc/CL10A226MO7JZN.do"
			(at 0 0 0)
			(layer "F.Fab")
			(hide yes)
			(effects
				(font
					(size 1.27 1.27)
					(thickness 0.15)
				)
			)
		)
		(property "Description" "SMD Multilayer Ceramic Capacitor"
			(at 0 0 0)
			(layer "F.Fab")
			(hide yes)
			(effects
				(font
					(size 1.27 1.27)
					(thickness 0.15)
				)
			)
		)
		(property "MPN" "CL10A226MO7JZNC"
			(at 0 0 180)
			(unlocked yes)
			(layer "F.Fab")
			(hide yes)
			(effects
				(font
					(size 1 1)
					(thickness 0.15)
				)
			)
		)
		(property "Manufacturer" "Samsung Electro-Mechanics"
			(at 0 0 180)
			(unlocked yes)
			(layer "F.Fab")
			(hide yes)
			(effects
				(font
					(size 1 1)
					(thickness 0.15)
				)
			)
		)
		(property "License" "Apache-2.0"
			(at 0 0 180)
			(unlocked yes)
			(layer "F.Fab")
			(hide yes)
			(effects
				(font
					(size 1 1)
					(thickness 0.15)
				)
			)
		)
		(property "Author" "Antmicro"
			(at 0 0 180)
			(unlocked yes)
			(layer "F.Fab")
			(hide yes)
			(effects
				(font
					(size 1 1)
					(thickness 0.15)
				)
			)
		)
		(property "Val" "22u"
			(at 0 0 180)
			(unlocked yes)
			(layer "F.Fab")
			(hide yes)
			(effects
				(font
					(size 1 1)
					(thickness 0.15)
				)
			)
		)
		(property "Voltage" "16V"
			(at 0 0 180)
			(unlocked yes)
			(layer "F.Fab")
			(hide yes)
			(effects
				(font
					(size 1 1)
					(thickness 0.15)
				)
			)
		)
		(property "Dielectric" ""
			(at 0 0 180)
			(unlocked yes)
			(layer "F.Fab")
			(hide yes)
			(effects
				(font
					(size 1 1)
					(thickness 0.15)
				)
			)
		)
		(property "Public" "False"
			(at 0 0 180)
			(unlocked yes)
			(layer "F.Fab")
			(hide yes)
			(effects
				(font
					(size 1 1)
					(thickness 0.15)
				)
			)
		)
		(sheetname "/Power/")
		(sheetfile "power.kicad_sch")
		(attr smd)
		(fp_line
			(start -0.15 0.55)
			(end 0.15 0.55)
			(stroke
				(width 0.15)
				(type solid)
			)
			(layer "F.SilkS")
		)
		(fp_line
			(start -0.15 -0.55)
			(end 0.15 -0.55)
			(stroke
				(width 0.15)
				(type solid)
			)
			(layer "F.SilkS")
		)
		(fp_rect
			(start -1.25 -0.65)
			(end 1.25 0.65)
			(stroke
				(width 0.05)
				(type solid)
			)
			(fill no)
			(layer "F.CrtYd")
		)
		(fp_rect
			(start -0.8 -0.45)
			(end 0.8 0.45)
			(stroke
				(width 0.15)
				(type solid)
			)
			(fill no)
			(layer "F.Fab")
		)
		(pad "1" smd roundrect
			(at -0.7 0 180)
			(size 0.8 1.1)
			(layers "F.Cu" "F.Mask" "F.Paste")
			(roundrect_rratio 0.2)
			(net 28 "GND")
			(pintype "passive")
		)
		(pad "2" smd roundrect
			(at 0.7 0 180)
			(size 0.8 1.1)
			(layers "F.Cu" "F.Mask" "F.Paste")
			(roundrect_rratio 0.2)
			(net 303 "/Power/+VCCD_OUT")
			(pintype "passive")
		)
	)
	(footprint "antmicro-footprints:C_0402_1005Metric"
		(layer "F.Cu")
		(at 69.1 98.95 180)
		(descr "Capacitor SMD 0402")
		(tags "capacitor SMD 0402")
		(property "Reference" "C138"
			(at 0.86 0.48 0)
			(layer "F.SilkS")
			(effects
				(font
					(size 0.7 0.7)
					(thickness 0.15)
				)
				(justify right top)
			)
		)
		(property "Value" "C_100n_0402"
			(at -1.022927 2.155213 0)
			(layer "F.Fab")
			(hide yes)
			(effects
				(font
					(size 0.7 0.7)
					(thickness 0.15)
				)
				(justify right top)
			)
		)
		(property "Datasheet" "https://www.murata.com/products/productdetail?partno=GRM155R61H104KE14%23"
			(at 0 0 0)
			(layer "F.Fab")
			(hide yes)
			(effects
				(font
					(size 1.27 1.27)
					(thickness 0.15)
				)
			)
		)
		(property "Description" "SMD Multilayer Ceramic Capacitor, 0.1 µF, 50 V, 0402 [1005 Metric], ± 10%, X5R, GRM Series"
			(at 0 0 0)
			(layer "F.Fab")
			(hide yes)
			(effects
				(font
					(size 1.27 1.27)
					(thickness 0.15)
				)
			)
		)
		(property "MPN" "GRM155R61H104KE14D"
			(at 0 0 180)
			(unlocked yes)
			(layer "F.Fab")
			(hide yes)
			(effects
				(font
					(size 1 1)
					(thickness 0.15)
				)
			)
		)
		(property "Val" "100n"
			(at 0 0 180)
			(unlocked yes)
			(layer "F.Fab")
			(hide yes)
			(effects
				(font
					(size 1 1)
					(thickness 0.15)
				)
			)
		)
		(property "Voltage" "50V"
			(at 0 0 180)
			(unlocked yes)
			(layer "F.Fab")
			(hide yes)
			(effects
				(font
					(size 1 1)
					(thickness 0.15)
				)
			)
		)
		(property "Dielectric" "X5R"
			(at 0 0 180)
			(unlocked yes)
			(layer "F.Fab")
			(hide yes)
			(effects
				(font
					(size 1 1)
					(thickness 0.15)
				)
			)
		)
		(property "Manufacturer" "Murata"
			(at 0 0 180)
			(unlocked yes)
			(layer "F.Fab")
			(hide yes)
			(effects
				(font
					(size 1 1)
					(thickness 0.15)
				)
			)
		)
		(property "License" "Apache-2.0"
			(at 0 0 180)
			(unlocked yes)
			(layer "F.Fab")
			(hide yes)
			(effects
				(font
					(size 1 1)
					(thickness 0.15)
				)
			)
		)
		(property "Author" "Antmicro"
			(at 0 0 180)
			(unlocked yes)
			(layer "F.Fab")
			(hide yes)
			(effects
				(font
					(size 1 1)
					(thickness 0.15)
				)
			)
		)
		(sheetname "/X710-AT2 power/")
		(sheetfile "x710-at2-power.kicad_sch")
		(attr smd)
		(fp_rect
			(start -0.925 -0.47)
			(end 0.925 0.47)
			(stroke
				(width 0.05)
				(type default)
			)
			(fill no)
			(layer "F.CrtYd")
		)
		(fp_line
			(start 0.504 0.248)
			(end -0.494 0.248)
			(stroke
				(width 0.15)
				(type solid)
			)
			(layer "F.Fab")
		)
		(fp_line
			(start 0.504 -0.25)
			(end 0.504 0.248)
			(stroke
				(width 0.15)
				(type solid)
			)
			(layer "F.Fab")
		)
		(fp_line
			(start -0.494 0.248)
			(end -0.494 -0.25)
			(stroke
				(width 0.15)
				(type solid)
			)
			(layer "F.Fab")
		)
		(fp_line
			(start -0.494 -0.25)
			(end 0.504 -0.25)
			(stroke
				(width 0.15)
				(type solid)
			)
			(layer "F.Fab")
		)
		(pad "1" smd roundrect
			(at -0.48 0 180)
			(size 0.59 0.64)
			(layers "F.Cu" "F.Mask" "F.Paste")
			(roundrect_rratio 0.25)
			(net 28 "GND")
			(pintype "passive")
		)
		(pad "2" smd roundrect
			(at 0.48 0 180)
			(size 0.59 0.64)
			(layers "F.Cu" "F.Mask" "F.Paste")
			(roundrect_rratio 0.25)
			(net 18 "+1V88")
			(pintype "passive")
		)
	)
	(footprint "antmicro-footprints:C_0603_1608Metric_EIA"
		(layer "F.Cu")
		(at 66.7 86.3 180)
		(descr "Capacitor SMD 0603, IPC-7351 Density Level A")
		(tags "Capacitor 0603")
		(property "Reference" "C127"
			(at -1.97 5.65 0)
			(layer "F.SilkS")
			(effects
				(font
					(size 0.7 0.7)
					(thickness 0.15)
				)
				(justify right top)
			)
		)
		(property "Value" "C_22u_16V_0603"
			(at -1.42757 1.770288 0)
			(layer "F.Fab")
			(hide yes)
			(effects
				(font
					(size 0.7 0.7)
					(thickness 0.15)
				)
				(justify right top)
			)
		)
		(property "Datasheet" "https://product.samsungsem.com/mlcc/CL10A226MO7JZN.do"
			(at 0 0 0)
			(layer "F.Fab")
			(hide yes)
			(effects
				(font
					(size 1.27 1.27)
					(thickness 0.15)
				)
			)
		)
		(property "Description" "SMD Multilayer Ceramic Capacitor"
			(at 0 0 0)
			(layer "F.Fab")
			(hide yes)
			(effects
				(font
					(size 1.27 1.27)
					(thickness 0.15)
				)
			)
		)
		(property "MPN" "CL10A226MO7JZNC"
			(at 0 0 180)
			(unlocked yes)
			(layer "F.Fab")
			(hide yes)
			(effects
				(font
					(size 1 1)
					(thickness 0.15)
				)
			)
		)
		(property "Manufacturer" "Samsung Electro-Mechanics"
			(at 0 0 180)
			(unlocked yes)
			(layer "F.Fab")
			(hide yes)
			(effects
				(font
					(size 1 1)
					(thickness 0.15)
				)
			)
		)
		(property "License" "Apache-2.0"
			(at 0 0 180)
			(unlocked yes)
			(layer "F.Fab")
			(hide yes)
			(effects
				(font
					(size 1 1)
					(thickness 0.15)
				)
			)
		)
		(property "Author" "Antmicro"
			(at 0 0 180)
			(unlocked yes)
			(layer "F.Fab")
			(hide yes)
			(effects
				(font
					(size 1 1)
					(thickness 0.15)
				)
			)
		)
		(property "Val" "22u"
			(at 0 0 180)
			(unlocked yes)
			(layer "F.Fab")
			(hide yes)
			(effects
				(font
					(size 1 1)
					(thickness 0.15)
				)
			)
		)
		(property "Voltage" "16V"
			(at 0 0 180)
			(unlocked yes)
			(layer "F.Fab")
			(hide yes)
			(effects
				(font
					(size 1 1)
					(thickness 0.15)
				)
			)
		)
		(property "Dielectric" ""
			(at 0 0 180)
			(unlocked yes)
			(layer "F.Fab")
			(hide yes)
			(effects
				(font
					(size 1 1)
					(thickness 0.15)
				)
			)
		)
		(sheetname "/X710-AT2 power/")
		(sheetfile "x710-at2-power.kicad_sch")
		(attr smd)
		(fp_line
			(start -0.15 0.55)
			(end 0.15 0.55)
			(stroke
				(width 0.15)
				(type solid)
			)
			(layer "F.SilkS")
		)
		(fp_line
			(start -0.15 -0.55)
			(end 0.15 -0.55)
			(stroke
				(width 0.15)
				(type solid)
			)
			(layer "F.SilkS")
		)
		(fp_rect
			(start -1.25 -0.65)
			(end 1.25 0.65)
			(stroke
				(width 0.05)
				(type solid)
			)
			(fill no)
			(layer "F.CrtYd")
		)
		(fp_rect
			(start -0.8 -0.45)
			(end 0.8 0.45)
			(stroke
				(width 0.15)
				(type solid)
			)
			(fill no)
			(layer "F.Fab")
		)
		(pad "1" smd roundrect
			(at -0.7 0 180)
			(size 0.8 1.1)
			(layers "F.Cu" "F.Mask" "F.Paste")
			(roundrect_rratio 0.2)
			(net 28 "GND")
			(pintype "passive")
		)
		(pad "2" smd roundrect
			(at 0.7 0 180)
			(size 0.8 1.1)
			(layers "F.Cu" "F.Mask" "F.Paste")
			(roundrect_rratio 0.2)
			(net 9 "VCCD")
			(pintype "passive")
		)
	)
)
